(kicad_pcb
	(version 20260206)
	(generator "pcbnew")
	(generator_version "10.0")
	(general
		(thickness 1.6)
		(legacy_teardrops no)
	)
	(paper "A4")
	(title_block
		(title "Bryce Canyon_SCC_16316-1_OCP.brd")
		(comment 1 "Bryce Canyon / footprints 633-641 of 1561")
	)
	(layers
		(0 "F.Cu" signal "TOP")
		(4 "In1.Cu" signal "L2GND")
		(6 "In2.Cu" signal "L3")
		(8 "In3.Cu" signal "L4VCC")
		(10 "In4.Cu" signal "L5VCC")
		(12 "In5.Cu" signal "L6")
		(14 "In6.Cu" signal "L7GND")
		(2 "B.Cu" signal "BOTTOM")
		(9 "F.Adhes" user "F.Adhesive")
		(11 "B.Adhes" user "B.Adhesive")
		(13 "F.Paste" user "Package Geometry/Pastemask Top")
		(15 "B.Paste" user "Package Geometry/Pastemask Bottom")
		(5 "F.SilkS" user "Ref Des/Silkscreen Top")
		(7 "B.SilkS" user "Ref Des/Silkscreen Bottom")
		(1 "F.Mask" user "Board Geometry/Soldermask Top")
		(3 "B.Mask" user "Board Geometry/Soldermask Bottom")
		(17 "Dwgs.User" user "User.Drawings")
		(19 "Cmts.User" user "User.Comments")
		(21 "Eco1.User" user "User.Eco1")
		(23 "Eco2.User" user "User.Eco2")
		(25 "Edge.Cuts" user "Board Geometry/Outline")
		(27 "Margin" user)
		(31 "F.CrtYd" user "Package Geometry/Place Bound Top")
		(29 "B.CrtYd" user "Package Geometry/Place Bound Bottom")
		(35 "F.Fab" user "Ref Des/Assembly Top")
		(33 "B.Fab" user "Ref Des/Assembly Bottom")
	)
	(footprint ""
		(layer "F.Cu")
		(at 70.485 -48.133 90)
		(property "Reference" "L18"
			(at 0 0 90)
			(layer "F.SilkS")
			(hide yes)
			(effects
				(font
					(size 1.27 1.27)
				)
			)
		)
		(property "Value" "MPZ2012S300AT-GP"
			(at 0 -4.2418 90)
			(unlocked yes)
			(layer "F.Fab")
			(hide yes)
			(effects
				(font
					(size 1.016 1.016)
					(thickness 0.1524)
				)
			)
		)
		(property "Device Type" "L805H42"
			(at 0 -5.7912 90)
			(unlocked yes)
			(layer "F.Fab")
			(hide yes)
			(effects
				(font
					(size 1.016 1.016)
					(thickness 0.1524)
				)
			)
		)
		(duplicate_pad_numbers_are_jumpers no)
		(fp_line
			(start 0.889 -1.7018)
			(end 0.889 1.7018)
			(stroke
				(width 0.1524)
				(type default)
			)
			(layer "F.SilkS")
		)
		(fp_line
			(start -0.889 -1.7018)
			(end 0.889 -1.7018)
			(stroke
				(width 0.1524)
				(type default)
			)
			(layer "F.SilkS")
		)
		(fp_line
			(start 0.889 1.7018)
			(end -0.889 1.7018)
			(stroke
				(width 0.1524)
				(type default)
			)
			(layer "F.SilkS")
		)
		(fp_line
			(start -0.889 1.7018)
			(end -0.889 -1.7018)
			(stroke
				(width 0.1524)
				(type default)
			)
			(layer "F.SilkS")
		)
		(fp_rect
			(start -0.9652 1.778)
			(end 0.9652 -1.778)
			(stroke
				(width 0)
				(type default)
			)
			(fill no)
			(layer "F.CrtYd")
		)
		(fp_rect
			(start -0.9652 1.778)
			(end 0.9652 -1.778)
			(stroke
				(width 0)
				(type default)
			)
			(fill no)
			(layer "F.Fab")
		)
		(pad "1" smd rect
			(at 0 -0.9652 90)
			(size 1.397 1.143)
			(layers "F.Cu" "F.Mask" "F.Paste")
			(net "P0V9")
		)
		(pad "2" smd rect
			(at 0 0.9652 90)
			(size 1.397 1.143)
			(layers "F.Cu" "F.Mask" "F.Paste")
			(net "GB_VDDA")
		)
	)
	(footprint ""
		(layer "F.Cu")
		(at 190.119 -27.8765 -90)
		(property "Reference" "TP75"
			(at 0 0 270)
			(layer "F.SilkS")
			(hide yes)
			(effects
				(font
					(size 1.27 1.27)
				)
			)
		)
		(property "Value" "TPAD28-2-GP"
			(at -0.0127 -1.6637 270)
			(unlocked yes)
			(layer "F.Fab")
			(hide yes)
			(effects
				(font
					(size 1.016 1.016)
					(thickness 0.1524)
				)
			)
		)
		(property "Device Type" "TPAD28"
			(at -0.0127 -3.1877 270)
			(unlocked yes)
			(layer "F.Fab")
			(hide yes)
			(effects
				(font
					(size 1.016 1.016)
					(thickness 0.1524)
				)
			)
		)
		(duplicate_pad_numbers_are_jumpers no)
		(fp_poly
			(pts
				(arc
					(start 0 -0.3556)
					(mid 0 0.3556)
					(end 0 -0.3556)
				)
			)
			(stroke
				(width 0)
				(type default)
			)
			(fill no)
			(layer "F.CrtYd")
		)
		(fp_poly
			(pts
				(arc
					(start 0 -0.6096)
					(mid 0 0.6096)
					(end 0 -0.6096)
				)
			)
			(stroke
				(width 0)
				(type default)
			)
			(fill no)
			(layer "F.Fab")
		)
		(pad "1" smd circle
			(at 0 0 270)
			(size 0.7112 0.7112)
			(layers "F.Cu" "F.Mask" "F.Paste")
			(net "IOC_GPIO_22")
		)
	)
	(footprint ""
		(layer "F.Cu")
		(at 170.162474 -99.677982 -90)
		(property "Reference" "R494"
			(at 0 0 270)
			(layer "F.SilkS")
			(hide yes)
			(effects
				(font
					(size 1.27 1.27)
				)
			)
		)
		(property "Value" "7K32R2F-GP"
			(at 0.064008 -3.993896 270)
			(unlocked yes)
			(layer "F.Fab")
			(hide yes)
			(effects
				(font
					(size 1.016 1.016)
					(thickness 0.1524)
				)
			)
		)
		(property "Device Type" "R402H16"
			(at 0.064008 -5.517896 270)
			(unlocked yes)
			(layer "F.Fab")
			(hide yes)
			(effects
				(font
					(size 1.016 1.016)
					(thickness 0.1524)
				)
			)
		)
		(duplicate_pad_numbers_are_jumpers no)
		(fp_line
			(start -0.508 -0.9398)
			(end -0.508 0.9398)
			(stroke
				(width 0.1524)
				(type default)
			)
			(layer "F.SilkS")
		)
		(fp_line
			(start 0.508 -0.9398)
			(end -0.508 -0.9398)
			(stroke
				(width 0.1524)
				(type default)
			)
			(layer "F.SilkS")
		)
		(fp_rect
			(start -0.508 0.9398)
			(end 0.508 -0.9398)
			(stroke
				(width 0)
				(type default)
			)
			(fill no)
			(layer "F.CrtYd")
		)
		(fp_rect
			(start -0.508 0.9398)
			(end 0.508 -0.9398)
			(stroke
				(width 0)
				(type default)
			)
			(fill no)
			(layer "F.Fab")
		)
		(pad "1" smd custom
			(at 0 -0.4445 270)
			(size 0.1397 0.1397)
			(layers "F.Cu" "F.Mask" "F.Paste")
			(net "VT235_VREF")
			(options
				(clearance outline)
				(anchor circle)
			)
			(primitives
				(gr_poly
					(pts
						(arc
							(start -0.1778 -0.2794)
							(mid -0.249642 -0.249642)
							(end -0.2794 -0.1778)
						)
						(arc
							(start -0.2794 0.1778)
							(mid -0.249642 0.249642)
							(end -0.1778 0.2794)
						)
						(arc
							(start 0.1778 0.2794)
							(mid 0.249642 0.249642)
							(end 0.2794 0.1778)
						)
						(arc
							(start 0.2794 -0.1778)
							(mid 0.249642 -0.249642)
							(end 0.1778 -0.2794)
						)
					)
					(width 0)
					(fill yes)
				)
			)
		)
		(pad "2" smd custom
			(at 0 0.4445 270)
			(size 0.1397 0.1397)
			(layers "F.Cu" "F.Mask" "F.Paste")
			(net "VT235_VDES_RR")
			(options
				(clearance outline)
				(anchor circle)
			)
			(primitives
				(gr_poly
					(pts
						(arc
							(start -0.1778 -0.2794)
							(mid -0.249642 -0.249642)
							(end -0.2794 -0.1778)
						)
						(arc
							(start -0.2794 0.1778)
							(mid -0.249642 0.249642)
							(end -0.1778 0.2794)
						)
						(arc
							(start 0.1778 0.2794)
							(mid 0.249642 0.249642)
							(end 0.2794 0.1778)
						)
						(arc
							(start 0.2794 -0.1778)
							(mid 0.249642 -0.249642)
							(end 0.1778 -0.2794)
						)
					)
					(width 0)
					(fill yes)
				)
			)
		)
	)
	(footprint ""
		(layer "F.Cu")
		(at 168.770808 -56.46801)
		(property "Reference" "TP122"
			(at 0 0 0)
			(layer "F.SilkS")
			(hide yes)
			(effects
				(font
					(size 1.27 1.27)
				)
			)
		)
		(property "Value" "TPAD28-2-GP"
			(at -0.0127 -1.6637 0)
			(unlocked yes)
			(layer "F.Fab")
			(hide yes)
			(effects
				(font
					(size 1.016 1.016)
					(thickness 0.1524)
				)
			)
		)
		(property "Device Type" "TPAD28"
			(at -0.0127 -3.1877 0)
			(unlocked yes)
			(layer "F.Fab")
			(hide yes)
			(effects
				(font
					(size 1.016 1.016)
					(thickness 0.1524)
				)
			)
		)
		(duplicate_pad_numbers_are_jumpers no)
		(fp_poly
			(pts
				(arc
					(start 0.3556 0)
					(mid -0.3556 0)
					(end 0.3556 0)
				)
			)
			(stroke
				(width 0)
				(type default)
			)
			(fill no)
			(layer "F.CrtYd")
		)
		(fp_poly
			(pts
				(arc
					(start 0.6096 0)
					(mid -0.6096 0)
					(end 0.6096 0)
				)
			)
			(stroke
				(width 0)
				(type default)
			)
			(fill no)
			(layer "F.Fab")
		)
		(pad "1" smd circle
			(at 0 0)
			(size 0.7112 0.7112)
			(layers "F.Cu" "F.Mask" "F.Paste")
			(net "ICE0_TDO")
		)
	)
	(footprint ""
		(layer "F.Cu")
		(at 13.362178 -43.193208 180)
		(property "Reference" "R520"
			(at 0 0 180)
			(layer "F.SilkS")
			(hide yes)
			(effects
				(font
					(size 1.27 1.27)
				)
			)
		)
		(property "Value" "10R2F-L-GP"
			(at 0.064008 -3.993896 180)
			(unlocked yes)
			(layer "F.Fab")
			(hide yes)
			(effects
				(font
					(size 1.016 1.016)
					(thickness 0.1524)
				)
			)
		)
		(property "Device Type" "R402H14"
			(at 0.064008 -5.517896 180)
			(unlocked yes)
			(layer "F.Fab")
			(hide yes)
			(effects
				(font
					(size 1.016 1.016)
					(thickness 0.1524)
				)
			)
		)
		(duplicate_pad_numbers_are_jumpers no)
		(fp_line
			(start 0.508 -0.9398)
			(end -0.508 -0.9398)
			(stroke
				(width 0.1524)
				(type default)
			)
			(layer "F.SilkS")
		)
		(fp_line
			(start -0.508 -0.9398)
			(end -0.508 0.9398)
			(stroke
				(width 0.1524)
				(type default)
			)
			(layer "F.SilkS")
		)
		(fp_rect
			(start -0.508 0.9398)
			(end 0.508 -0.9398)
			(stroke
				(width 0)
				(type default)
			)
			(fill no)
			(layer "F.CrtYd")
		)
		(fp_rect
			(start -0.508 0.9398)
			(end 0.508 -0.9398)
			(stroke
				(width 0)
				(type default)
			)
			(fill no)
			(layer "F.Fab")
		)
		(pad "1" smd custom
			(at 0 -0.4445 180)
			(size 0.1397 0.1397)
			(layers "F.Cu" "F.Mask" "F.Paste")
			(net "MB0_CM_SENSE_R1_N")
			(options
				(clearance outline)
				(anchor circle)
			)
			(primitives
				(gr_poly
					(pts
						(arc
							(start -0.1778 -0.2794)
							(mid -0.249642 -0.249642)
							(end -0.2794 -0.1778)
						)
						(arc
							(start -0.2794 0.1778)
							(mid -0.249642 0.249642)
							(end -0.1778 0.2794)
						)
						(arc
							(start 0.1778 0.2794)
							(mid 0.249642 0.249642)
							(end 0.2794 0.1778)
						)
						(arc
							(start 0.2794 -0.1778)
							(mid 0.249642 -0.249642)
							(end 0.1778 -0.2794)
						)
					)
					(width 0)
					(fill yes)
				)
			)
		)
		(pad "2" smd custom
			(at 0 0.4445 180)
			(size 0.1397 0.1397)
			(layers "F.Cu" "F.Mask" "F.Paste")
			(net "MB0_CM_SENSE_N")
			(options
				(clearance outline)
				(anchor circle)
			)
			(primitives
				(gr_poly
					(pts
						(arc
							(start -0.1778 -0.2794)
							(mid -0.249642 -0.249642)
							(end -0.2794 -0.1778)
						)
						(arc
							(start -0.2794 0.1778)
							(mid -0.249642 0.249642)
							(end -0.1778 0.2794)
						)
						(arc
							(start 0.1778 0.2794)
							(mid 0.249642 0.249642)
							(end 0.2794 0.1778)
						)
						(arc
							(start 0.2794 -0.1778)
							(mid 0.249642 -0.249642)
							(end 0.1778 -0.2794)
						)
					)
					(width 0)
					(fill yes)
				)
			)
		)
	)
	(footprint ""
		(layer "F.Cu")
		(at 148.02358 -119.00662 -90)
		(property "Reference" "R27"
			(at 0 0 270)
			(layer "F.SilkS")
			(hide yes)
			(effects
				(font
					(size 1.27 1.27)
				)
			)
		)
		(property "Value" "10KR2F-2-GP"
			(at 0.064008 -3.993896 270)
			(unlocked yes)
			(layer "F.Fab")
			(hide yes)
			(effects
				(font
					(size 1.016 1.016)
					(thickness 0.1524)
				)
			)
		)
		(property "Device Type" "R402H16"
			(at 0.064008 -5.517896 270)
			(unlocked yes)
			(layer "F.Fab")
			(hide yes)
			(effects
				(font
					(size 1.016 1.016)
					(thickness 0.1524)
				)
			)
		)
		(duplicate_pad_numbers_are_jumpers no)
		(fp_line
			(start -0.508 -0.9398)
			(end -0.508 0.9398)
			(stroke
				(width 0.1524)
				(type default)
			)
			(layer "F.SilkS")
		)
		(fp_line
			(start 0.508 -0.9398)
			(end -0.508 -0.9398)
			(stroke
				(width 0.1524)
				(type default)
			)
			(layer "F.SilkS")
		)
		(fp_rect
			(start -0.508 0.9398)
			(end 0.508 -0.9398)
			(stroke
				(width 0)
				(type default)
			)
			(fill no)
			(layer "F.CrtYd")
		)
		(fp_rect
			(start -0.508 0.9398)
			(end 0.508 -0.9398)
			(stroke
				(width 0)
				(type default)
			)
			(fill no)
			(layer "F.Fab")
		)
		(pad "1" smd custom
			(at 0 -0.4445 270)
			(size 0.1397 0.1397)
			(layers "F.Cu" "F.Mask" "F.Paste")
			(net "P1V5_E_PG")
			(options
				(clearance outline)
				(anchor circle)
			)
			(primitives
				(gr_poly
					(pts
						(arc
							(start -0.1778 -0.2794)
							(mid -0.249642 -0.249642)
							(end -0.2794 -0.1778)
						)
						(arc
							(start -0.2794 0.1778)
							(mid -0.249642 0.249642)
							(end -0.1778 0.2794)
						)
						(arc
							(start 0.1778 0.2794)
							(mid 0.249642 0.249642)
							(end 0.2794 0.1778)
						)
						(arc
							(start 0.2794 -0.1778)
							(mid 0.249642 -0.249642)
							(end 0.1778 -0.2794)
						)
					)
					(width 0)
					(fill yes)
				)
			)
		)
		(pad "2" smd custom
			(at 0 0.4445 270)
			(size 0.1397 0.1397)
			(layers "F.Cu" "F.Mask" "F.Paste")
			(net "P3V3")
			(options
				(clearance outline)
				(anchor circle)
			)
			(primitives
				(gr_poly
					(pts
						(arc
							(start -0.1778 -0.2794)
							(mid -0.249642 -0.249642)
							(end -0.2794 -0.1778)
						)
						(arc
							(start -0.2794 0.1778)
							(mid -0.249642 0.249642)
							(end -0.1778 0.2794)
						)
						(arc
							(start 0.1778 0.2794)
							(mid 0.249642 0.249642)
							(end 0.2794 0.1778)
						)
						(arc
							(start 0.2794 -0.1778)
							(mid 0.249642 -0.249642)
							(end 0.1778 -0.2794)
						)
					)
					(width 0)
					(fill yes)
				)
			)
		)
	)
	(footprint ""
		(layer "F.Cu")
		(at 49.089056 -34.899092)
		(property "Reference" "PSP1"
			(at 0 0 0)
			(layer "F.SilkS")
			(hide yes)
			(effects
				(font
					(size 1.27 1.27)
				)
			)
		)
		(property "Value" "COPPER-CLOSE-GP-U"
			(at 0.0762 -2.8702 0)
			(unlocked yes)
			(layer "F.Fab")
			(hide yes)
			(effects
				(font
					(size 1.016 1.016)
					(thickness 0.1524)
				)
			)
		)
		(property "Device Type" "CON2C-U"
			(at 0.0762 -4.3942 0)
			(unlocked yes)
			(layer "F.Fab")
			(hide yes)
			(effects
				(font
					(size 1.016 1.016)
					(thickness 0.1524)
				)
			)
		)
		(duplicate_pad_numbers_are_jumpers no)
		(fp_rect
			(start -0.9398 0.9652)
			(end 0.9398 -0.9652)
			(stroke
				(width 0)
				(type default)
			)
			(fill no)
			(layer "F.CrtYd")
		)
		(fp_rect
			(start -0.9398 0.9652)
			(end 0.9398 -0.9652)
			(stroke
				(width 0)
				(type default)
			)
			(fill no)
			(layer "F.Fab")
		)
		(pad "1" smd custom
			(at 0 -0.5334)
			(size 0.17145 0.17145)
			(layers "F.Cu" "F.Mask" "F.Paste")
			(net "GND")
			(options
				(clearance outline)
				(anchor circle)
			)
			(primitives
				(gr_poly
					(pts
						(xy -0.127 0.3429) (xy -0.127 0.1651) (xy -0.635 -0.3429) (xy 0.635 -0.3429) (xy 0.127 0.1651)
						(xy 0.127 0.3429)
					)
					(width 0)
					(fill yes)
				)
			)
		)
		(pad "2" smd custom
			(at 0 0.5334)
			(size 0.17145 0.17145)
			(layers "F.Cu" "F.Mask" "F.Paste")
			(net "AGND_P0V9")
			(options
				(clearance outline)
				(anchor circle)
			)
			(primitives
				(gr_poly
					(pts
						(xy -0.635 0.3429) (xy -0.127 -0.1651) (xy -0.127 -0.3429) (xy 0.127 -0.3429) (xy 0.127 -0.1651)
						(xy 0.635 0.3429)
					)
					(width 0)
					(fill yes)
				)
			)
		)
	)
	(footprint ""
		(layer "F.Cu")
		(at 159.722312 -92.563696 90)
		(property "Reference" "R286"
			(at 0 0 90)
			(layer "F.SilkS")
			(hide yes)
			(effects
				(font
					(size 1.27 1.27)
				)
			)
		)
		(property "Value" "10KR2F-2-GP"
			(at 0.064008 -3.993896 90)
			(unlocked yes)
			(layer "F.Fab")
			(hide yes)
			(effects
				(font
					(size 1.016 1.016)
					(thickness 0.1524)
				)
			)
		)
		(property "Device Type" "R402H16"
			(at 0.064008 -5.517896 90)
			(unlocked yes)
			(layer "F.Fab")
			(hide yes)
			(effects
				(font
					(size 1.016 1.016)
					(thickness 0.1524)
				)
			)
		)
		(duplicate_pad_numbers_are_jumpers no)
		(fp_line
			(start 0.508 -0.9398)
			(end -0.508 -0.9398)
			(stroke
				(width 0.1524)
				(type default)
			)
			(layer "F.SilkS")
		)
		(fp_line
			(start -0.508 -0.9398)
			(end -0.508 0.9398)
			(stroke
				(width 0.1524)
				(type default)
			)
			(layer "F.SilkS")
		)
		(fp_rect
			(start -0.508 0.9398)
			(end 0.508 -0.9398)
			(stroke
				(width 0)
				(type default)
			)
			(fill no)
			(layer "F.CrtYd")
		)
		(fp_rect
			(start -0.508 0.9398)
			(end 0.508 -0.9398)
			(stroke
				(width 0)
				(type default)
			)
			(fill no)
			(layer "F.Fab")
		)
		(pad "1" smd custom
			(at 0 -0.4445 90)
			(size 0.1397 0.1397)
			(layers "F.Cu" "F.Mask" "F.Paste")
			(net "SMART_UART_EN")
			(options
				(clearance outline)
				(anchor circle)
			)
			(primitives
				(gr_poly
					(pts
						(arc
							(start -0.1778 -0.2794)
							(mid -0.249642 -0.249642)
							(end -0.2794 -0.1778)
						)
						(arc
							(start -0.2794 0.1778)
							(mid -0.249642 0.249642)
							(end -0.1778 0.2794)
						)
						(arc
							(start 0.1778 0.2794)
							(mid 0.249642 0.249642)
							(end 0.2794 0.1778)
						)
						(arc
							(start 0.2794 -0.1778)
							(mid 0.249642 -0.249642)
							(end 0.1778 -0.2794)
						)
					)
					(width 0)
					(fill yes)
				)
			)
		)
		(pad "2" smd custom
			(at 0 0.4445 90)
			(size 0.1397 0.1397)
			(layers "F.Cu" "F.Mask" "F.Paste")
			(net "P1V8_E")
			(options
				(clearance outline)
				(anchor circle)
			)
			(primitives
				(gr_poly
					(pts
						(arc
							(start -0.1778 -0.2794)
							(mid -0.249642 -0.249642)
							(end -0.2794 -0.1778)
						)
						(arc
							(start -0.2794 0.1778)
							(mid -0.249642 0.249642)
							(end -0.1778 0.2794)
						)
						(arc
							(start 0.1778 0.2794)
							(mid 0.249642 0.249642)
							(end 0.2794 0.1778)
						)
						(arc
							(start 0.2794 -0.1778)
							(mid 0.249642 -0.249642)
							(end 0.1778 -0.2794)
						)
					)
					(width 0)
					(fill yes)
				)
			)
		)
	)
	(footprint ""
		(layer "F.Cu")
		(at 128.863598 -87.265002 180)
		(property "Reference" "R101"
			(at 0 0 180)
			(layer "F.SilkS")
			(hide yes)
			(effects
				(font
					(size 1.27 1.27)
				)
			)
		)
		(property "Value" "0R2J-2-GP"
			(at 0.064008 -3.993896 180)
			(unlocked yes)
			(layer "F.Fab")
			(hide yes)
			(effects
				(font
					(size 1.016 1.016)
					(thickness 0.1524)
				)
			)
		)
		(property "Device Type" "R402H16"
			(at 0.064008 -5.517896 180)
			(unlocked yes)
			(layer "F.Fab")
			(hide yes)
			(effects
				(font
					(size 1.016 1.016)
					(thickness 0.1524)
				)
			)
		)
		(duplicate_pad_numbers_are_jumpers no)
		(fp_line
			(start 0.508 -0.9398)
			(end -0.508 -0.9398)
			(stroke
				(width 0.1524)
				(type default)
			)
			(layer "F.SilkS")
		)
		(fp_line
			(start -0.508 -0.9398)
			(end -0.508 0.9398)
			(stroke
				(width 0.1524)
				(type default)
			)
			(layer "F.SilkS")
		)
		(fp_rect
			(start -0.508 0.9398)
			(end 0.508 -0.9398)
			(stroke
				(width 0)
				(type default)
			)
			(fill no)
			(layer "F.CrtYd")
		)
		(fp_rect
			(start -0.508 0.9398)
			(end 0.508 -0.9398)
			(stroke
				(width 0)
				(type default)
			)
			(fill no)
			(layer "F.Fab")
		)
		(pad "1" smd custom
			(at 0 -0.4445 180)
			(size 0.1397 0.1397)
			(layers "F.Cu" "F.Mask" "F.Paste")
			(net "SMART_TX")
			(options
				(clearance outline)
				(anchor circle)
			)
			(primitives
				(gr_poly
					(pts
						(arc
							(start -0.1778 -0.2794)
							(mid -0.249642 -0.249642)
							(end -0.2794 -0.1778)
						)
						(arc
							(start -0.2794 0.1778)
							(mid -0.249642 0.249642)
							(end -0.1778 0.2794)
						)
						(arc
							(start 0.1778 0.2794)
							(mid 0.249642 0.249642)
							(end 0.2794 0.1778)
						)
						(arc
							(start 0.2794 -0.1778)
							(mid 0.249642 -0.249642)
							(end 0.1778 -0.2794)
						)
					)
					(width 0)
					(fill yes)
				)
			)
		)
		(pad "2" smd custom
			(at 0 0.4445 180)
			(size 0.1397 0.1397)
			(layers "F.Cu" "F.Mask" "F.Paste")
			(net "SAS_SMART_TX")
			(options
				(clearance outline)
				(anchor circle)
			)
			(primitives
				(gr_poly
					(pts
						(arc
							(start -0.1778 -0.2794)
							(mid -0.249642 -0.249642)
							(end -0.2794 -0.1778)
						)
						(arc
							(start -0.2794 0.1778)
							(mid -0.249642 0.249642)
							(end -0.1778 0.2794)
						)
						(arc
							(start 0.1778 0.2794)
							(mid 0.249642 0.249642)
							(end 0.2794 0.1778)
						)
						(arc
							(start 0.2794 -0.1778)
							(mid 0.249642 -0.249642)
							(end 0.1778 -0.2794)
						)
					)
					(width 0)
					(fill yes)
				)
			)
		)
	)
)
